(kicad_pcb
	(version 20260206)
	(generator "pcbnew")
	(generator_version "10.0")
	(general
		(thickness 1.6)
		(legacy_teardrops no)
	)
	(paper "A4")
	(title_block
		(title "baseboard — 13948-1b.1110WZS1818.brd")
		(comment 1 "Honey Badger (Wiwynn) / footprints 886-892 of 2523")
	)
	(layers
		(0 "F.Cu" signal "TOP")
		(4 "In1.Cu" signal "L2GND")
		(6 "In2.Cu" signal "L3")
		(8 "In3.Cu" signal "L4VCC")
		(10 "In4.Cu" signal "L5VCC")
		(12 "In5.Cu" signal "L6")
		(14 "In6.Cu" signal "L7GND")
		(2 "B.Cu" signal "BOTTOM")
		(9 "F.Adhes" user "F.Adhesive")
		(11 "B.Adhes" user "B.Adhesive")
		(13 "F.Paste" user "Package Geometry/Pastemask Top")
		(15 "B.Paste" user "Package Geometry/Pastemask Bottom")
		(5 "F.SilkS" user "Ref Des/Silkscreen Top")
		(7 "B.SilkS" user "Ref Des/Silkscreen Bottom")
		(1 "F.Mask" user "Board Geometry/Soldermask Top")
		(3 "B.Mask" user "Board Geometry/Soldermask Bottom")
		(17 "Dwgs.User" user "User.Drawings")
		(19 "Cmts.User" user "User.Comments")
		(21 "Eco1.User" user "User.Eco1")
		(23 "Eco2.User" user "User.Eco2")
		(25 "Edge.Cuts" user "Board Geometry/Outline")
		(27 "Margin" user)
		(31 "F.CrtYd" user "Package Geometry/Place Bound Top")
		(29 "B.CrtYd" user "Package Geometry/Place Bound Bottom")
		(35 "F.Fab" user "Ref Des/Assembly Top")
		(33 "B.Fab" user "Ref Des/Assembly Bottom")
	)
	(footprint ""
		(layer "F.Cu")
		(at 23.564088 -181.865016)
		(property "Reference" "SR313"
			(at 0 0 0)
			(layer "F.SilkS")
			(hide yes)
			(effects
				(font
					(size 1.27 1.27)
				)
			)
		)
		(property "Value" "0R2J-2-GP"
			(at 0.064008 -3.993896 0)
			(unlocked yes)
			(layer "F.Fab")
			(hide yes)
			(effects
				(font
					(size 1.016 1.016)
					(thickness 0.1524)
				)
			)
		)
		(property "Device Type" "R402H16"
			(at 0.064008 -5.517896 0)
			(unlocked yes)
			(layer "F.Fab")
			(hide yes)
			(effects
				(font
					(size 1.016 1.016)
					(thickness 0.1524)
				)
			)
		)
		(duplicate_pad_numbers_are_jumpers no)
		(fp_line
			(start -0.508 -0.9398)
			(end -0.508 0.9398)
			(stroke
				(width 0.1524)
				(type default)
			)
			(layer "F.SilkS")
		)
		(fp_line
			(start 0.508 -0.9398)
			(end -0.508 -0.9398)
			(stroke
				(width 0.1524)
				(type default)
			)
			(layer "F.SilkS")
		)
		(fp_rect
			(start -0.508 0.9398)
			(end 0.508 -0.9398)
			(stroke
				(width 0)
				(type default)
			)
			(fill no)
			(layer "F.CrtYd")
		)
		(fp_rect
			(start -0.508 0.9398)
			(end 0.508 -0.9398)
			(stroke
				(width 0)
				(type default)
			)
			(fill no)
			(layer "F.Fab")
		)
		(pad "1" smd custom
			(at 0 -0.4445)
			(size 0.1397 0.1397)
			(layers "F.Cu" "F.Mask" "F.Paste")
			(net "PRE_SDA")
			(options
				(clearance outline)
				(anchor circle)
			)
			(primitives
				(gr_poly
					(pts
						(arc
							(start -0.1778 -0.2794)
							(mid -0.249642 -0.249642)
							(end -0.2794 -0.1778)
						)
						(arc
							(start -0.2794 0.1778)
							(mid -0.249642 0.249642)
							(end -0.1778 0.2794)
						)
						(arc
							(start 0.1778 0.2794)
							(mid 0.249642 0.249642)
							(end 0.2794 0.1778)
						)
						(arc
							(start 0.2794 -0.1778)
							(mid 0.249642 -0.249642)
							(end 0.1778 -0.2794)
						)
					)
					(width 0)
					(fill yes)
				)
			)
		)
		(pad "2" smd custom
			(at 0 0.4445)
			(size 0.1397 0.1397)
			(layers "F.Cu" "F.Mask" "F.Paste")
			(net "BMC_IOEXP_SDA_10")
			(options
				(clearance outline)
				(anchor circle)
			)
			(primitives
				(gr_poly
					(pts
						(arc
							(start -0.1778 -0.2794)
							(mid -0.249642 -0.249642)
							(end -0.2794 -0.1778)
						)
						(arc
							(start -0.2794 0.1778)
							(mid -0.249642 0.249642)
							(end -0.1778 0.2794)
						)
						(arc
							(start 0.1778 0.2794)
							(mid 0.249642 0.249642)
							(end 0.2794 0.1778)
						)
						(arc
							(start 0.2794 -0.1778)
							(mid 0.249642 -0.249642)
							(end 0.1778 -0.2794)
						)
					)
					(width 0)
					(fill yes)
				)
			)
		)
	)
	(footprint ""
		(layer "F.Cu")
		(at 90.18397 -139.954 180)
		(property "Reference" "R157"
			(at 0 0 180)
			(layer "F.SilkS")
			(hide yes)
			(effects
				(font
					(size 1.27 1.27)
				)
			)
		)
		(property "Value" "0R2J-2-GP"
			(at 0.064008 -3.993896 180)
			(unlocked yes)
			(layer "F.Fab")
			(hide yes)
			(effects
				(font
					(size 1.016 1.016)
					(thickness 0.1524)
				)
			)
		)
		(property "Device Type" "R402H16"
			(at 0.064008 -5.517896 180)
			(unlocked yes)
			(layer "F.Fab")
			(hide yes)
			(effects
				(font
					(size 1.016 1.016)
					(thickness 0.1524)
				)
			)
		)
		(duplicate_pad_numbers_are_jumpers no)
		(fp_line
			(start 0.508 -0.9398)
			(end -0.508 -0.9398)
			(stroke
				(width 0.1524)
				(type default)
			)
			(layer "F.SilkS")
		)
		(fp_line
			(start -0.508 -0.9398)
			(end -0.508 0.9398)
			(stroke
				(width 0.1524)
				(type default)
			)
			(layer "F.SilkS")
		)
		(fp_rect
			(start -0.508 0.9398)
			(end 0.508 -0.9398)
			(stroke
				(width 0)
				(type default)
			)
			(fill no)
			(layer "F.CrtYd")
		)
		(fp_rect
			(start -0.508 0.9398)
			(end 0.508 -0.9398)
			(stroke
				(width 0)
				(type default)
			)
			(fill no)
			(layer "F.Fab")
		)
		(pad "1" smd custom
			(at 0 -0.4445 180)
			(size 0.1397 0.1397)
			(layers "F.Cu" "F.Mask" "F.Paste")
			(net "EXP_SELF_TRAY")
			(options
				(clearance outline)
				(anchor circle)
			)
			(primitives
				(gr_poly
					(pts
						(arc
							(start -0.1778 -0.2794)
							(mid -0.249642 -0.249642)
							(end -0.2794 -0.1778)
						)
						(arc
							(start -0.2794 0.1778)
							(mid -0.249642 0.249642)
							(end -0.1778 0.2794)
						)
						(arc
							(start 0.1778 0.2794)
							(mid 0.249642 0.249642)
							(end 0.2794 0.1778)
						)
						(arc
							(start 0.2794 -0.1778)
							(mid 0.249642 -0.249642)
							(end 0.1778 -0.2794)
						)
					)
					(width 0)
					(fill yes)
				)
			)
		)
		(pad "2" smd custom
			(at 0 0.4445 180)
			(size 0.1397 0.1397)
			(layers "F.Cu" "F.Mask" "F.Paste")
			(net "SELF_TRAY")
			(options
				(clearance outline)
				(anchor circle)
			)
			(primitives
				(gr_poly
					(pts
						(arc
							(start -0.1778 -0.2794)
							(mid -0.249642 -0.249642)
							(end -0.2794 -0.1778)
						)
						(arc
							(start -0.2794 0.1778)
							(mid -0.249642 0.249642)
							(end -0.1778 0.2794)
						)
						(arc
							(start 0.1778 0.2794)
							(mid 0.249642 0.249642)
							(end 0.2794 0.1778)
						)
						(arc
							(start 0.2794 -0.1778)
							(mid 0.249642 -0.249642)
							(end 0.1778 -0.2794)
						)
					)
					(width 0)
					(fill yes)
				)
			)
		)
	)
	(footprint ""
		(layer "F.Cu")
		(at 96.66097 -118.3005 180)
		(property "Reference" "SR745"
			(at 0 0 180)
			(layer "F.SilkS")
			(hide yes)
			(effects
				(font
					(size 1.27 1.27)
				)
			)
		)
		(property "Value" "4K7R2F-GP"
			(at 0.064008 -3.993896 180)
			(unlocked yes)
			(layer "F.Fab")
			(hide yes)
			(effects
				(font
					(size 1.016 1.016)
					(thickness 0.1524)
				)
			)
		)
		(property "Device Type" "R402H16"
			(at 0.064008 -5.517896 180)
			(unlocked yes)
			(layer "F.Fab")
			(hide yes)
			(effects
				(font
					(size 1.016 1.016)
					(thickness 0.1524)
				)
			)
		)
		(duplicate_pad_numbers_are_jumpers no)
		(fp_line
			(start 0.508 -0.9398)
			(end -0.508 -0.9398)
			(stroke
				(width 0.1524)
				(type default)
			)
			(layer "F.SilkS")
		)
		(fp_line
			(start -0.508 -0.9398)
			(end -0.508 0.9398)
			(stroke
				(width 0.1524)
				(type default)
			)
			(layer "F.SilkS")
		)
		(fp_rect
			(start -0.508 0.9398)
			(end 0.508 -0.9398)
			(stroke
				(width 0)
				(type default)
			)
			(fill no)
			(layer "F.CrtYd")
		)
		(fp_rect
			(start -0.508 0.9398)
			(end 0.508 -0.9398)
			(stroke
				(width 0)
				(type default)
			)
			(fill no)
			(layer "F.Fab")
		)
		(pad "1" smd custom
			(at 0 -0.4445 180)
			(size 0.1397 0.1397)
			(layers "F.Cu" "F.Mask" "F.Paste")
			(net "EXP_SIO_CLK_IN")
			(options
				(clearance outline)
				(anchor circle)
			)
			(primitives
				(gr_poly
					(pts
						(arc
							(start -0.1778 -0.2794)
							(mid -0.249642 -0.249642)
							(end -0.2794 -0.1778)
						)
						(arc
							(start -0.2794 0.1778)
							(mid -0.249642 0.249642)
							(end -0.1778 0.2794)
						)
						(arc
							(start 0.1778 0.2794)
							(mid 0.249642 0.249642)
							(end 0.2794 0.1778)
						)
						(arc
							(start 0.2794 -0.1778)
							(mid 0.249642 -0.249642)
							(end 0.1778 -0.2794)
						)
					)
					(width 0)
					(fill yes)
				)
			)
		)
		(pad "2" smd custom
			(at 0 0.4445 180)
			(size 0.1397 0.1397)
			(layers "F.Cu" "F.Mask" "F.Paste")
			(net "P1V8_E")
			(options
				(clearance outline)
				(anchor circle)
			)
			(primitives
				(gr_poly
					(pts
						(arc
							(start -0.1778 -0.2794)
							(mid -0.249642 -0.249642)
							(end -0.2794 -0.1778)
						)
						(arc
							(start -0.2794 0.1778)
							(mid -0.249642 0.249642)
							(end -0.1778 0.2794)
						)
						(arc
							(start 0.1778 0.2794)
							(mid 0.249642 0.249642)
							(end 0.2794 0.1778)
						)
						(arc
							(start 0.2794 -0.1778)
							(mid 0.249642 -0.249642)
							(end 0.1778 -0.2794)
						)
					)
					(width 0)
					(fill yes)
				)
			)
		)
	)
	(footprint ""
		(layer "F.Cu")
		(at 159.893 -155.6766 -90)
		(property "Reference" "SR727"
			(at 0 0 270)
			(layer "F.SilkS")
			(hide yes)
			(effects
				(font
					(size 1.27 1.27)
				)
			)
		)
		(property "Value" "0R2J-2-GP"
			(at 0.064008 -3.993896 270)
			(unlocked yes)
			(layer "F.Fab")
			(hide yes)
			(effects
				(font
					(size 1.016 1.016)
					(thickness 0.1524)
				)
			)
		)
		(property "Device Type" "R402H16"
			(at 0.064008 -5.517896 270)
			(unlocked yes)
			(layer "F.Fab")
			(hide yes)
			(effects
				(font
					(size 1.016 1.016)
					(thickness 0.1524)
				)
			)
		)
		(duplicate_pad_numbers_are_jumpers no)
		(fp_line
			(start -0.508 -0.9398)
			(end -0.508 0.9398)
			(stroke
				(width 0.1524)
				(type default)
			)
			(layer "F.SilkS")
		)
		(fp_line
			(start 0.508 -0.9398)
			(end -0.508 -0.9398)
			(stroke
				(width 0.1524)
				(type default)
			)
			(layer "F.SilkS")
		)
		(fp_rect
			(start -0.508 0.9398)
			(end 0.508 -0.9398)
			(stroke
				(width 0)
				(type default)
			)
			(fill no)
			(layer "F.CrtYd")
		)
		(fp_rect
			(start -0.508 0.9398)
			(end 0.508 -0.9398)
			(stroke
				(width 0)
				(type default)
			)
			(fill no)
			(layer "F.Fab")
		)
		(pad "1" smd custom
			(at 0 -0.4445 270)
			(size 0.1397 0.1397)
			(layers "F.Cu" "F.Mask" "F.Paste")
			(net "IOC_P3V3_R_SCL_14")
			(options
				(clearance outline)
				(anchor circle)
			)
			(primitives
				(gr_poly
					(pts
						(arc
							(start -0.1778 -0.2794)
							(mid -0.249642 -0.249642)
							(end -0.2794 -0.1778)
						)
						(arc
							(start -0.2794 0.1778)
							(mid -0.249642 0.249642)
							(end -0.1778 0.2794)
						)
						(arc
							(start 0.1778 0.2794)
							(mid 0.249642 0.249642)
							(end 0.2794 0.1778)
						)
						(arc
							(start 0.2794 -0.1778)
							(mid 0.249642 -0.249642)
							(end 0.1778 -0.2794)
						)
					)
					(width 0)
					(fill yes)
				)
			)
		)
		(pad "2" smd custom
			(at 0 0.4445 270)
			(size 0.1397 0.1397)
			(layers "F.Cu" "F.Mask" "F.Paste")
			(net "IOC_P3V3_SCL_14")
			(options
				(clearance outline)
				(anchor circle)
			)
			(primitives
				(gr_poly
					(pts
						(arc
							(start -0.1778 -0.2794)
							(mid -0.249642 -0.249642)
							(end -0.2794 -0.1778)
						)
						(arc
							(start -0.2794 0.1778)
							(mid -0.249642 0.249642)
							(end -0.1778 0.2794)
						)
						(arc
							(start 0.1778 0.2794)
							(mid 0.249642 0.249642)
							(end 0.2794 0.1778)
						)
						(arc
							(start 0.2794 -0.1778)
							(mid 0.249642 -0.249642)
							(end 0.1778 -0.2794)
						)
					)
					(width 0)
					(fill yes)
				)
			)
		)
	)
	(footprint ""
		(layer "F.Cu")
		(at 152.019 -52.07 90)
		(property "Reference" "SR698"
			(at 0 0 90)
			(layer "F.SilkS")
			(hide yes)
			(effects
				(font
					(size 1.27 1.27)
				)
			)
		)
		(property "Value" "10KR2F-2-GP"
			(at 0.064008 -3.993896 90)
			(unlocked yes)
			(layer "F.Fab")
			(hide yes)
			(effects
				(font
					(size 1.016 1.016)
					(thickness 0.1524)
				)
			)
		)
		(property "Device Type" "R402H16"
			(at 0.064008 -5.517896 90)
			(unlocked yes)
			(layer "F.Fab")
			(hide yes)
			(effects
				(font
					(size 1.016 1.016)
					(thickness 0.1524)
				)
			)
		)
		(duplicate_pad_numbers_are_jumpers no)
		(fp_line
			(start 0.508 -0.9398)
			(end -0.508 -0.9398)
			(stroke
				(width 0.1524)
				(type default)
			)
			(layer "F.SilkS")
		)
		(fp_line
			(start -0.508 -0.9398)
			(end -0.508 0.9398)
			(stroke
				(width 0.1524)
				(type default)
			)
			(layer "F.SilkS")
		)
		(fp_rect
			(start -0.508 0.9398)
			(end 0.508 -0.9398)
			(stroke
				(width 0)
				(type default)
			)
			(fill no)
			(layer "F.CrtYd")
		)
		(fp_rect
			(start -0.508 0.9398)
			(end 0.508 -0.9398)
			(stroke
				(width 0)
				(type default)
			)
			(fill no)
			(layer "F.Fab")
		)
		(pad "1" smd custom
			(at 0 -0.4445 90)
			(size 0.1397 0.1397)
			(layers "F.Cu" "F.Mask" "F.Paste")
			(net "XM_ADDR_4")
			(options
				(clearance outline)
				(anchor circle)
			)
			(primitives
				(gr_poly
					(pts
						(arc
							(start -0.1778 -0.2794)
							(mid -0.249642 -0.249642)
							(end -0.2794 -0.1778)
						)
						(arc
							(start -0.2794 0.1778)
							(mid -0.249642 0.249642)
							(end -0.1778 0.2794)
						)
						(arc
							(start 0.1778 0.2794)
							(mid 0.249642 0.249642)
							(end 0.2794 0.1778)
						)
						(arc
							(start 0.2794 -0.1778)
							(mid 0.249642 -0.249642)
							(end 0.1778 -0.2794)
						)
					)
					(width 0)
					(fill yes)
				)
			)
		)
		(pad "2" smd custom
			(at 0 0.4445 90)
			(size 0.1397 0.1397)
			(layers "F.Cu" "F.Mask" "F.Paste")
			(net "GND")
			(options
				(clearance outline)
				(anchor circle)
			)
			(primitives
				(gr_poly
					(pts
						(arc
							(start -0.1778 -0.2794)
							(mid -0.249642 -0.249642)
							(end -0.2794 -0.1778)
						)
						(arc
							(start -0.2794 0.1778)
							(mid -0.249642 0.249642)
							(end -0.1778 0.2794)
						)
						(arc
							(start 0.1778 0.2794)
							(mid 0.249642 0.249642)
							(end 0.2794 0.1778)
						)
						(arc
							(start 0.2794 -0.1778)
							(mid 0.249642 -0.249642)
							(end 0.1778 -0.2794)
						)
					)
					(width 0)
					(fill yes)
				)
			)
		)
	)
	(footprint ""
		(layer "F.Cu")
		(at 92.27947 -105.283 90)
		(property "Reference" "SR819"
			(at 0 0 90)
			(layer "F.SilkS")
			(hide yes)
			(effects
				(font
					(size 1.27 1.27)
				)
			)
		)
		(property "Value" "4K75R2F-1-GP"
			(at 0.064008 -3.993896 90)
			(unlocked yes)
			(layer "F.Fab")
			(hide yes)
			(effects
				(font
					(size 1.016 1.016)
					(thickness 0.1524)
				)
			)
		)
		(property "Device Type" "R402H16"
			(at 0.064008 -5.517896 90)
			(unlocked yes)
			(layer "F.Fab")
			(hide yes)
			(effects
				(font
					(size 1.016 1.016)
					(thickness 0.1524)
				)
			)
		)
		(duplicate_pad_numbers_are_jumpers no)
		(fp_line
			(start 0.508 -0.9398)
			(end -0.508 -0.9398)
			(stroke
				(width 0.1524)
				(type default)
			)
			(layer "F.SilkS")
		)
		(fp_line
			(start -0.508 -0.9398)
			(end -0.508 0.9398)
			(stroke
				(width 0.1524)
				(type default)
			)
			(layer "F.SilkS")
		)
		(fp_rect
			(start -0.508 0.9398)
			(end 0.508 -0.9398)
			(stroke
				(width 0)
				(type default)
			)
			(fill no)
			(layer "F.CrtYd")
		)
		(fp_rect
			(start -0.508 0.9398)
			(end 0.508 -0.9398)
			(stroke
				(width 0)
				(type default)
			)
			(fill no)
			(layer "F.Fab")
		)
		(pad "1" smd custom
			(at 0 -0.4445 90)
			(size 0.1397 0.1397)
			(layers "F.Cu" "F.Mask" "F.Paste")
			(net "P1V8_E")
			(options
				(clearance outline)
				(anchor circle)
			)
			(primitives
				(gr_poly
					(pts
						(arc
							(start -0.1778 -0.2794)
							(mid -0.249642 -0.249642)
							(end -0.2794 -0.1778)
						)
						(arc
							(start -0.2794 0.1778)
							(mid -0.249642 0.249642)
							(end -0.1778 0.2794)
						)
						(arc
							(start 0.1778 0.2794)
							(mid 0.249642 0.249642)
							(end 0.2794 0.1778)
						)
						(arc
							(start 0.2794 -0.1778)
							(mid 0.249642 -0.249642)
							(end 0.1778 -0.2794)
						)
					)
					(width 0)
					(fill yes)
				)
			)
		)
		(pad "2" smd custom
			(at 0 0.4445 90)
			(size 0.1397 0.1397)
			(layers "F.Cu" "F.Mask" "F.Paste")
			(net "SAS_SMART_TX")
			(options
				(clearance outline)
				(anchor circle)
			)
			(primitives
				(gr_poly
					(pts
						(arc
							(start -0.1778 -0.2794)
							(mid -0.249642 -0.249642)
							(end -0.2794 -0.1778)
						)
						(arc
							(start -0.2794 0.1778)
							(mid -0.249642 0.249642)
							(end -0.1778 0.2794)
						)
						(arc
							(start 0.1778 0.2794)
							(mid 0.249642 0.249642)
							(end 0.2794 0.1778)
						)
						(arc
							(start 0.2794 -0.1778)
							(mid 0.249642 -0.249642)
							(end 0.1778 -0.2794)
						)
					)
					(width 0)
					(fill yes)
				)
			)
		)
	)
	(footprint ""
		(layer "F.Cu")
		(at 78.848966 -67.564 180)
		(property "Reference" "SC983"
			(at 0 0 180)
			(layer "F.SilkS")
			(hide yes)
			(effects
				(font
					(size 1.27 1.27)
				)
			)
		)
		(property "Value" "SCD1U16V2KX-3GP"
			(at 1.1811 -2.7051 180)
			(unlocked yes)
			(layer "F.Fab")
			(hide yes)
			(effects
				(font
					(size 1.016 1.016)
					(thickness 0.1524)
				)
			)
		)
		(property "Device Type" "C402H22"
			(at 1.1811 -4.2291 180)
			(unlocked yes)
			(layer "F.Fab")
			(hide yes)
			(effects
				(font
					(size 1.016 1.016)
					(thickness 0.1524)
				)
			)
		)
		(duplicate_pad_numbers_are_jumpers no)
		(fp_rect
			(start -0.4318 0.9525)
			(end 0.4318 -0.9525)
			(stroke
				(width 0)
				(type default)
			)
			(fill no)
			(layer "F.CrtYd")
		)
		(fp_rect
			(start -0.4318 0.9525)
			(end 0.4318 -0.9525)
			(stroke
				(width 0)
				(type default)
			)
			(fill no)
			(layer "F.Fab")
		)
		(pad "1" smd custom
			(at 0 -0.4445 180)
			(size 0.1524 0.1524)
			(layers "F.Cu" "F.Mask" "F.Paste")
			(net "P1V8_C")
			(options
				(clearance outline)
				(anchor circle)
			)
			(primitives
				(gr_poly
					(pts
						(arc
							(start 0.3048 -0.2032)
							(mid 0.275042 -0.275042)
							(end 0.2032 -0.3048)
						)
						(arc
							(start -0.2032 -0.3048)
							(mid -0.275042 -0.275042)
							(end -0.3048 -0.2032)
						)
						(arc
							(start -0.3048 0.2032)
							(mid -0.275042 0.275042)
							(end -0.2032 0.3048)
						)
						(arc
							(start 0.2032 0.3048)
							(mid 0.275042 0.275042)
							(end 0.3048 0.2032)
						)
					)
					(width 0)
					(fill yes)
				)
			)
		)
		(pad "2" smd custom
			(at 0 0.4445 180)
			(size 0.1524 0.1524)
			(layers "F.Cu" "F.Mask" "F.Paste")
			(net "GND")
			(options
				(clearance outline)
				(anchor circle)
			)
			(primitives
				(gr_poly
					(pts
						(arc
							(start 0.3048 -0.2032)
							(mid 0.275042 -0.275042)
							(end 0.2032 -0.3048)
						)
						(arc
							(start -0.2032 -0.3048)
							(mid -0.275042 -0.275042)
							(end -0.3048 -0.2032)
						)
						(arc
							(start -0.3048 0.2032)
							(mid -0.275042 0.275042)
							(end -0.2032 0.3048)
						)
						(arc
							(start 0.2032 0.3048)
							(mid 0.275042 0.275042)
							(end 0.3048 0.2032)
						)
					)
					(width 0)
					(fill yes)
				)
			)
		)
	)
)
